FILE_TYPE = MACRO_DRAWING;
SET COLOR_WIRE YELLOW;
SET COLOR_PROP ORANGE;
SET COLOR_DOT WHITE;
SET COLOR_ARC YELLOW;
SET COLOR_BODY GREEN;
SET COLOR_NOTE PURPLE;
SET PROP_DISPLAY VALUE;
SET PAGE_NUMBER P130;
FORCEADD Q_RES..1
(-5200 -350);
FORCEPROP 1 LAST PART_NUMBER CS00002JB13
J 0
(-5300 -275);
DISPLAY 0.510638 (-5300 -275);
DISPLAY INVISIBLE (-5300 -275);
FORCEPROP 1 LAST PACK_TYPE 0402LF
J 0
(-4950 -350);
DISPLAY 0.638298 (-4950 -350);
FORCEPROP 1 LAST TOLERANCE 5%
J 0
(-5025 -350);
DISPLAY 0.638298 (-5025 -350);
FORCEPROP 1 LAST VALUE 0
J 2
(-5050 -350);
DISPLAY 0.638298 (-5050 -350);
FORCEPROP 1 LAST MATERIAL CHIP
J 0
(-5300 -225);
DISPLAY 0.510638 (-5300 -225);
FORCEPROP 1 LAST WATTAGE 1/16W
J 2
(-5075 -225);
DISPLAY 0.510638 (-5075 -225);
FORCEPROP 1 LAST $LOCATION R815
J 0
(-5400 -350);
DISPLAY 0.638298 (-5400 -350);
FORCEPROP 1 LASTPIN (-5300 -350) $PN 1
J 0
(-5288 -338);
DISPLAY 0.787234 (-5288 -338);
FORCEPROP 1 LASTPIN (-5100 -350) $PN 2
J 0
(-5138 -338);
DISPLAY 0.787234 (-5138 -338);
FORCEPROP 2 LAST CDS_LIB pure_quanta
J 0
(-5200 -350);
PAINT MONO (-5200 -350);
DISPLAY INVISIBLE (-5200 -350);
FORCEPROP 1 LAST PATH I11
J 0
(-5250 -200);
DISPLAY 0.978723 (-5250 -200);
PAINT WHITE (-5250 -200);
DISPLAY INVISIBLE (-5250 -200);
FORCEPROP 1 LAST $LOCATION R815
J 0
(-5250 -150);
DISPLAY 1.021277 (-5250 -150);
DISPLAY INVISIBLE (-5250 -150);
FORCEPROP 2 LAST CDS_LOCATION R815
J 0
(-5250 -150);
DISPLAY 1.021277 (-5250 -150);
DISPLAY INVISIBLE (-5250 -150);
FORCEPROP 2 LAST $SEC 1
J 0
(-5250 -150);
DISPLAY 0.680851 (-5250 -150);
PAINT MONO (-5250 -150);
DISPLAY INVISIBLE (-5250 -150);
FORCEPROP 2 LAST CDS_SEC 1
J 0
(-5250 -150);
DISPLAY 1.021277 (-5250 -150);
DISPLAY INVISIBLE (-5250 -150);
FORCEADD Q_RES..1
(-5175 1175);
FORCEPROP 1 LAST PART_NUMBER CS00002JB13
J 0
(-5275 1250);
DISPLAY 0.510638 (-5275 1250);
DISPLAY INVISIBLE (-5275 1250);
FORCEPROP 1 LAST TOLERANCE 5%
J 0
(-5000 1175);
DISPLAY 0.638298 (-5000 1175);
FORCEPROP 1 LAST VALUE 0
J 2
(-5025 1175);
DISPLAY 0.638298 (-5025 1175);
FORCEPROP 1 LAST PACK_TYPE 0402LF
J 0
(-4925 1175);
DISPLAY 0.638298 (-4925 1175);
FORCEPROP 1 LAST WATTAGE 1/16W
J 2
(-5050 1300);
DISPLAY 0.510638 (-5050 1300);
FORCEPROP 1 LAST MATERIAL CHIP
J 0
(-5275 1300);
DISPLAY 0.510638 (-5275 1300);
FORCEPROP 1 LAST $LOCATION R818
J 0
(-5375 1175);
DISPLAY 0.638298 (-5375 1175);
FORCEPROP 1 LASTPIN (-5275 1175) $PN 1
J 0
(-5263 1187);
DISPLAY 0.787234 (-5263 1187);
FORCEPROP 1 LASTPIN (-5075 1175) $PN 2
J 0
(-5113 1187);
DISPLAY 0.787234 (-5113 1187);
FORCEPROP 2 LAST CDS_LIB pure_quanta
J 0
(-5175 1175);
PAINT MONO (-5175 1175);
DISPLAY INVISIBLE (-5175 1175);
FORCEPROP 1 LAST PATH I22
J 0
(-5225 1325);
DISPLAY 0.978723 (-5225 1325);
PAINT WHITE (-5225 1325);
DISPLAY INVISIBLE (-5225 1325);
FORCEPROP 1 LAST $LOCATION R818
J 0
(-5225 1375);
DISPLAY 1.021277 (-5225 1375);
DISPLAY INVISIBLE (-5225 1375);
FORCEPROP 2 LAST CDS_LOCATION R818
J 0
(-5225 1375);
DISPLAY 1.021277 (-5225 1375);
DISPLAY INVISIBLE (-5225 1375);
FORCEPROP 2 LAST $SEC 1
J 0
(-5225 1375);
DISPLAY 0.680851 (-5225 1375);
PAINT MONO (-5225 1375);
DISPLAY INVISIBLE (-5225 1375);
FORCEPROP 2 LAST CDS_SEC 1
J 0
(-5225 1375);
DISPLAY 1.021277 (-5225 1375);
DISPLAY INVISIBLE (-5225 1375);
FORCEADD Q_RES..1
(-5175 2675);
FORCEPROP 1 LAST PART_NUMBER CS00002JB13
J 0
(-5275 2750);
DISPLAY 0.510638 (-5275 2750);
DISPLAY INVISIBLE (-5275 2750);
FORCEPROP 1 LAST MATERIAL CHIP
J 0
(-5275 2800);
DISPLAY 0.510638 (-5275 2800);
FORCEPROP 1 LAST WATTAGE 1/16W
J 2
(-5050 2800);
DISPLAY 0.510638 (-5050 2800);
FORCEPROP 1 LAST PACK_TYPE 0402LF
J 0
(-4925 2675);
DISPLAY 0.638298 (-4925 2675);
FORCEPROP 1 LAST TOLERANCE 5%
J 0
(-5000 2675);
DISPLAY 0.638298 (-5000 2675);
FORCEPROP 1 LAST VALUE 0
J 2
(-5025 2675);
DISPLAY 0.638298 (-5025 2675);
FORCEPROP 1 LAST $LOCATION R817
J 0
(-5375 2675);
DISPLAY 0.638298 (-5375 2675);
FORCEPROP 1 LASTPIN (-5275 2675) $PN 1
J 0
(-5263 2687);
DISPLAY 0.787234 (-5263 2687);
FORCEPROP 1 LASTPIN (-5075 2675) $PN 2
J 0
(-5113 2687);
DISPLAY 0.787234 (-5113 2687);
FORCEPROP 2 LAST CDS_LIB pure_quanta
J 0
(-5175 2675);
PAINT MONO (-5175 2675);
DISPLAY INVISIBLE (-5175 2675);
FORCEPROP 1 LAST PATH I26
J 0
(-5225 2825);
DISPLAY 0.978723 (-5225 2825);
PAINT WHITE (-5225 2825);
DISPLAY INVISIBLE (-5225 2825);
FORCEPROP 1 LAST $LOCATION R817
J 0
(-5225 2875);
DISPLAY 1.021277 (-5225 2875);
DISPLAY INVISIBLE (-5225 2875);
FORCEPROP 2 LAST CDS_LOCATION R817
J 0
(-5225 2875);
DISPLAY 1.021277 (-5225 2875);
DISPLAY INVISIBLE (-5225 2875);
FORCEPROP 2 LAST $SEC 1
J 0
(-5225 2875);
DISPLAY 0.680851 (-5225 2875);
PAINT MONO (-5225 2875);
DISPLAY INVISIBLE (-5225 2875);
FORCEPROP 2 LAST CDS_SEC 1
J 0
(-5225 2875);
DISPLAY 1.021277 (-5225 2875);
DISPLAY INVISIBLE (-5225 2875);
FORCEADD Q_RES..1
(-5175 4200);
FORCEPROP 1 LAST PART_NUMBER CS00002JB13
J 0
(-5275 4275);
DISPLAY 0.510638 (-5275 4275);
DISPLAY INVISIBLE (-5275 4275);
FORCEPROP 1 LAST MATERIAL CHIP
J 0
(-5275 4325);
DISPLAY 0.510638 (-5275 4325);
FORCEPROP 1 LAST VALUE 0
J 2
(-5025 4200);
DISPLAY 0.638298 (-5025 4200);
FORCEPROP 1 LAST TOLERANCE 5%
J 0
(-5000 4200);
DISPLAY 0.638298 (-5000 4200);
FORCEPROP 1 LAST WATTAGE 1/16W
J 2
(-5050 4325);
DISPLAY 0.510638 (-5050 4325);
FORCEPROP 1 LAST PACK_TYPE 0402LF
J 0
(-4925 4200);
DISPLAY 0.638298 (-4925 4200);
FORCEPROP 1 LAST $LOCATION R816
J 0
(-5375 4200);
DISPLAY 0.638298 (-5375 4200);
FORCEPROP 1 LASTPIN (-5275 4200) $PN 1
J 0
(-5263 4212);
DISPLAY 0.787234 (-5263 4212);
FORCEPROP 1 LASTPIN (-5075 4200) $PN 2
J 0
(-5113 4212);
DISPLAY 0.787234 (-5113 4212);
FORCEPROP 2 LAST CDS_LIB pure_quanta
J 0
(-5175 4200);
PAINT MONO (-5175 4200);
DISPLAY INVISIBLE (-5175 4200);
FORCEPROP 1 LAST PATH I37
J 0
(-5225 4350);
DISPLAY 0.978723 (-5225 4350);
PAINT WHITE (-5225 4350);
DISPLAY INVISIBLE (-5225 4350);
FORCEPROP 1 LAST $LOCATION R816
J 0
(-5225 4400);
DISPLAY 1.021277 (-5225 4400);
DISPLAY INVISIBLE (-5225 4400);
FORCEPROP 2 LAST CDS_LOCATION R816
J 0
(-5225 4400);
DISPLAY 1.021277 (-5225 4400);
DISPLAY INVISIBLE (-5225 4400);
FORCEPROP 2 LAST $SEC 1
J 0
(-5225 4400);
DISPLAY 0.680851 (-5225 4400);
PAINT MONO (-5225 4400);
DISPLAY INVISIBLE (-5225 4400);
FORCEPROP 2 LAST CDS_SEC 1
J 0
(-5225 4400);
DISPLAY 1.021277 (-5225 4400);
DISPLAY INVISIBLE (-5225 4400);
FORCEADD OFFPAGE..1
(-8650 -350);
FORCEPROP 2 LAST $XR1 256 
J 0
(-9052 -350);
DISPLAY 0.638298 (-9052 -350);
PAINT MONO (-9052 -350);
FORCEPROP 2 LAST $XR0 216 
J 0
(-8932 -350);
DISPLAY 0.638298 (-8932 -350);
PAINT MONO (-8932 -350);
FORCEPROP 2 LAST CDS_LIB standard
J 0
(-8650 -350);
PAINT MONO (-8650 -350);
DISPLAY INVISIBLE (-8650 -350);
FORCEPROP 1 LAST OFFPAGE TRUE
J 0
(-8325 -475);
DISPLAY 0.872340 (-8325 -475);
PAINT GREEN (-8325 -475);
DISPLAY INVISIBLE (-8325 -475);
FORCEPROP 1 LAST COMMENT_BODY TRUE
J 0
(-8525 -450);
DISPLAY 0.872340 (-8525 -450);
PAINT GREEN (-8525 -450);
DISPLAY INVISIBLE (-8525 -450);
FORCEPROP 2 LAST PATH I53
J 0
(-8925 -300);
DISPLAY 1.021277 (-8925 -300);
DISPLAY INVISIBLE (-8925 -300);
FORCEADD OFFPAGE..1
(-8625 1175);
FORCEPROP 2 LAST $XR1 256 
J 0
(-8997 1175);
DISPLAY 0.638298 (-8997 1175);
PAINT MONO (-8997 1175);
FORCEPROP 2 LAST $XR0 216 
J 0
(-8877 1175);
DISPLAY 0.638298 (-8877 1175);
PAINT MONO (-8877 1175);
FORCEPROP 2 LAST CDS_LIB standard
J 0
(-8625 1175);
PAINT MONO (-8625 1175);
DISPLAY INVISIBLE (-8625 1175);
FORCEPROP 1 LAST OFFPAGE TRUE
J 0
(-8300 1050);
DISPLAY 0.872340 (-8300 1050);
PAINT GREEN (-8300 1050);
DISPLAY INVISIBLE (-8300 1050);
FORCEPROP 1 LAST COMMENT_BODY TRUE
J 0
(-8500 1075);
DISPLAY 0.872340 (-8500 1075);
PAINT GREEN (-8500 1075);
DISPLAY INVISIBLE (-8500 1075);
FORCEPROP 2 LAST PATH I54
J 0
(-8900 1225);
DISPLAY 1.021277 (-8900 1225);
DISPLAY INVISIBLE (-8900 1225);
FORCEADD OFFPAGE..1
(-8625 2675);
FORCEPROP 2 LAST $XR1 256 
J 0
(-8997 2675);
DISPLAY 0.638298 (-8997 2675);
PAINT MONO (-8997 2675);
FORCEPROP 2 LAST $XR0 216 
J 0
(-8877 2675);
DISPLAY 0.638298 (-8877 2675);
PAINT MONO (-8877 2675);
FORCEPROP 2 LAST CDS_LIB standard
J 0
(-8625 2675);
PAINT MONO (-8625 2675);
DISPLAY INVISIBLE (-8625 2675);
FORCEPROP 1 LAST OFFPAGE TRUE
J 0
(-8300 2550);
DISPLAY 0.872340 (-8300 2550);
PAINT GREEN (-8300 2550);
DISPLAY INVISIBLE (-8300 2550);
FORCEPROP 1 LAST COMMENT_BODY TRUE
J 0
(-8500 2575);
DISPLAY 0.872340 (-8500 2575);
PAINT GREEN (-8500 2575);
DISPLAY INVISIBLE (-8500 2575);
FORCEPROP 2 LAST PATH I55
J 0
(-8900 2725);
DISPLAY 1.021277 (-8900 2725);
DISPLAY INVISIBLE (-8900 2725);
FORCEADD OFFPAGE..1
(-8625 4200);
FORCEPROP 2 LAST $XR1 256 
J 0
(-8997 4200);
DISPLAY 0.638298 (-8997 4200);
PAINT MONO (-8997 4200);
FORCEPROP 2 LAST $XR0 216 
J 0
(-8877 4200);
DISPLAY 0.638298 (-8877 4200);
PAINT MONO (-8877 4200);
FORCEPROP 2 LAST CDS_LIB standard
J 0
(-8625 4200);
PAINT MONO (-8625 4200);
DISPLAY INVISIBLE (-8625 4200);
FORCEPROP 1 LAST OFFPAGE TRUE
J 0
(-8300 4075);
DISPLAY 0.872340 (-8300 4075);
PAINT GREEN (-8300 4075);
DISPLAY INVISIBLE (-8300 4075);
FORCEPROP 1 LAST COMMENT_BODY TRUE
J 0
(-8500 4100);
DISPLAY 0.872340 (-8500 4100);
PAINT GREEN (-8500 4100);
DISPLAY INVISIBLE (-8500 4100);
FORCEPROP 2 LAST PATH I56
J 0
(-8900 4250);
DISPLAY 1.021277 (-8900 4250);
DISPLAY INVISIBLE (-8900 4250);
FORCEADD UNIVERSAL_GND..1
(-7750 -950);
FORCEPROP 3 LASTPIN (-7750 -900) SIG_NAME GND\g
J 0
(-7740 -890);
DISPLAY 0.659574 (-7740 -890);
PAINT MONO (-7740 -890);
DISPLAY INVISIBLE (-7740 -890);
FORCEPROP 2 LAST CDS_LIB logical_power
J 0
(-7750 -950);
PAINT MONO (-7750 -950);
DISPLAY INVISIBLE (-7750 -950);
FORCEPROP 1 LAST HDL_POWER GND
J 1
(-7725 -1025);
DISPLAY 0.872340 (-7725 -1025);
PAINT GREEN (-7725 -1025);
DISPLAY INVISIBLE (-7725 -1025);
FORCEPROP 1 LAST PATH I57
J 0
(-7675 -950);
DISPLAY 0.872340 (-7675 -950);
PAINT AQUA (-7675 -950);
DISPLAY INVISIBLE (-7675 -950);
FORCEADD UNIVERSAL_GND..1
(-7725 575);
FORCEPROP 3 LASTPIN (-7725 625) SIG_NAME GND\g
J 0
(-7715 635);
DISPLAY 0.659574 (-7715 635);
PAINT MONO (-7715 635);
DISPLAY INVISIBLE (-7715 635);
FORCEPROP 2 LAST CDS_LIB logical_power
J 0
(-7725 575);
PAINT MONO (-7725 575);
DISPLAY INVISIBLE (-7725 575);
FORCEPROP 1 LAST HDL_POWER GND
J 1
(-7700 500);
DISPLAY 0.872340 (-7700 500);
PAINT GREEN (-7700 500);
DISPLAY INVISIBLE (-7700 500);
FORCEPROP 1 LAST PATH I58
J 0
(-7650 575);
DISPLAY 0.872340 (-7650 575);
PAINT AQUA (-7650 575);
DISPLAY INVISIBLE (-7650 575);
FORCEADD Q_CAP..1
R 2
(-7725 875);
FORCEPROP 1 LAST PART_NUMBER CH5104KEB02
J 2
(-7775 725);
DISPLAY 0.510638 (-7775 725);
DISPLAY INVISIBLE (-7775 725);
FORCEPROP 1 LAST VALUE 1UF
J 2
(-7775 925);
DISPLAY 0.510638 (-7775 925);
FORCEPROP 1 LAST VOLTAGE 25V
J 2
(-7775 875);
DISPLAY 0.510638 (-7775 875);
FORCEPROP 1 LAST TOLERANCE 10%
J 2
(-7775 825);
DISPLAY 0.510638 (-7775 825);
FORCEPROP 1 LAST PACK_TYPE C0402
J 2
(-7775 675);
DISPLAY 0.510638 (-7775 675);
FORCEPROP 1 LAST MATERIAL EMPTY
J 2
(-7775 775);
DISPLAY 0.510638 (-7775 775);
FORCEPROP 1 LAST $LOCATION C616
J 2
(-7775 975);
DISPLAY 0.978723 (-7775 975);
FORCEPROP 1 LASTPIN (-7725 975) $PN 1
J 2
(-7735 955);
DISPLAY 0.787234 (-7735 955);
FORCEPROP 1 LASTPIN (-7725 775) $PN 2
J 2
(-7735 755);
DISPLAY 0.787234 (-7735 755);
FORCEPROP 2 LAST CDS_LIB pure_quanta
J 0
(-7725 875);
PAINT MONO (-7725 875);
DISPLAY INVISIBLE (-7725 875);
FORCEPROP 1 LAST PATH I59
J 2
(-7775 1025);
DISPLAY 0.978723 (-7775 1025);
PAINT WHITE (-7775 1025);
DISPLAY INVISIBLE (-7775 1025);
FORCEPROP 2 LAST CDS_LOCATION C616
J 0
(-7775 1075);
DISPLAY 1.021277 (-7775 1075);
DISPLAY INVISIBLE (-7775 1075);
FORCEPROP 2 LAST $SEC 1
J 0
(-7775 1075);
DISPLAY 0.680851 (-7775 1075);
PAINT MONO (-7775 1075);
DISPLAY INVISIBLE (-7775 1075);
FORCEPROP 2 LAST CDS_SEC 1
J 0
(-7775 1075);
DISPLAY 1.021277 (-7775 1075);
DISPLAY INVISIBLE (-7775 1075);
FORCEADD UNIVERSAL_GND..1
(-7725 2075);
FORCEPROP 3 LASTPIN (-7725 2125) SIG_NAME GND\g
J 0
(-7715 2135);
DISPLAY 0.659574 (-7715 2135);
PAINT MONO (-7715 2135);
DISPLAY INVISIBLE (-7715 2135);
FORCEPROP 2 LAST CDS_LIB logical_power
J 0
(-7725 2075);
PAINT MONO (-7725 2075);
DISPLAY INVISIBLE (-7725 2075);
FORCEPROP 1 LAST HDL_POWER GND
J 1
(-7700 2000);
DISPLAY 0.872340 (-7700 2000);
PAINT GREEN (-7700 2000);
DISPLAY INVISIBLE (-7700 2000);
FORCEPROP 1 LAST PATH I61
J 0
(-7650 2075);
DISPLAY 0.872340 (-7650 2075);
PAINT AQUA (-7650 2075);
DISPLAY INVISIBLE (-7650 2075);
FORCEADD Q_CAP..1
R 2
(-7725 2375);
FORCEPROP 1 LAST PART_NUMBER CH5104KEB02
J 2
(-7775 2225);
DISPLAY 0.510638 (-7775 2225);
DISPLAY INVISIBLE (-7775 2225);
FORCEPROP 1 LAST PACK_TYPE C0402
J 2
(-7775 2175);
DISPLAY 0.510638 (-7775 2175);
FORCEPROP 1 LAST VOLTAGE 25V
J 2
(-7775 2375);
DISPLAY 0.510638 (-7775 2375);
FORCEPROP 1 LAST VALUE 1UF
J 2
(-7775 2425);
DISPLAY 0.510638 (-7775 2425);
FORCEPROP 1 LAST TOLERANCE 10%
J 2
(-7775 2325);
DISPLAY 0.510638 (-7775 2325);
FORCEPROP 1 LAST MATERIAL EMPTY
J 2
(-7775 2275);
DISPLAY 0.510638 (-7775 2275);
PAINT RED (-7775 2275);
FORCEPROP 1 LAST $LOCATION C615
J 2
(-7775 2475);
DISPLAY 0.978723 (-7775 2475);
FORCEPROP 1 LASTPIN (-7725 2475) $PN 1
J 2
(-7735 2455);
DISPLAY 0.787234 (-7735 2455);
FORCEPROP 1 LASTPIN (-7725 2275) $PN 2
J 2
(-7735 2255);
DISPLAY 0.787234 (-7735 2255);
FORCEPROP 2 LAST CDS_LIB pure_quanta
J 0
(-7725 2375);
PAINT MONO (-7725 2375);
DISPLAY INVISIBLE (-7725 2375);
FORCEPROP 1 LAST PATH I62
J 2
(-7775 2525);
DISPLAY 0.978723 (-7775 2525);
PAINT WHITE (-7775 2525);
DISPLAY INVISIBLE (-7775 2525);
FORCEPROP 2 LAST CDS_LOCATION C615
J 0
(-7775 2575);
DISPLAY 1.021277 (-7775 2575);
DISPLAY INVISIBLE (-7775 2575);
FORCEPROP 2 LAST $SEC 1
J 0
(-7775 2575);
DISPLAY 0.680851 (-7775 2575);
PAINT MONO (-7775 2575);
DISPLAY INVISIBLE (-7775 2575);
FORCEPROP 2 LAST CDS_SEC 1
J 0
(-7775 2575);
DISPLAY 1.021277 (-7775 2575);
DISPLAY INVISIBLE (-7775 2575);
FORCEADD Q_RES..2
(-7625 2400);
FORCEPROP 1 LAST PART_NUMBER CS31002FB08
J 0
(-7585 2225);
DISPLAY 0.510638 (-7585 2225);
DISPLAY INVISIBLE (-7585 2225);
FORCEPROP 1 LAST VALUE 10K
J 0
(-7580 2425);
DISPLAY 0.510638 (-7580 2425);
FORCEPROP 1 LAST TOLERANCE 1%
J 0
(-7580 2375);
DISPLAY 0.510638 (-7580 2375);
FORCEPROP 1 LAST WATTAGE 1/16W
J 0
(-7585 2325);
DISPLAY 0.510638 (-7585 2325);
FORCEPROP 1 LAST MATERIAL EMPTY
J 0
(-7585 2275);
DISPLAY 0.510638 (-7585 2275);
PAINT RED (-7585 2275);
FORCEPROP 1 LAST PACK_TYPE 0402LF
J 0
(-7585 2175);
DISPLAY 0.510638 (-7585 2175);
FORCEPROP 1 LAST $LOCATION R701
J 0
(-7580 2475);
DISPLAY 1.021277 (-7580 2475);
FORCEPROP 1 LASTPIN (-7625 2500) $PN 1
J 0
(-7620 2462);
DISPLAY 0.787234 (-7620 2462);
FORCEPROP 1 LASTPIN (-7625 2300) $PN 2
J 0
(-7620 2310);
DISPLAY 0.787234 (-7620 2310);
FORCEPROP 2 LAST CDS_LIB pure_quanta
J 0
(-7625 2400);
PAINT MONO (-7625 2400);
DISPLAY INVISIBLE (-7625 2400);
FORCEPROP 1 LAST PATH I63
J 0
(-7575 2575);
DISPLAY 0.978723 (-7575 2575);
PAINT WHITE (-7575 2575);
DISPLAY INVISIBLE (-7575 2575);
FORCEPROP 2 LAST CDS_LOCATION R701
J 0
(-7575 2625);
DISPLAY 1.021277 (-7575 2625);
DISPLAY INVISIBLE (-7575 2625);
FORCEPROP 2 LAST $SEC 1
J 0
(-7575 2625);
DISPLAY 0.680851 (-7575 2625);
PAINT MONO (-7575 2625);
DISPLAY INVISIBLE (-7575 2625);
FORCEPROP 2 LAST CDS_SEC 1
J 0
(-7575 2625);
DISPLAY 1.021277 (-7575 2625);
DISPLAY INVISIBLE (-7575 2625);
FORCEADD UNIVERSAL_GND..1
(-7725 3600);
FORCEPROP 3 LASTPIN (-7725 3650) SIG_NAME GND\g
J 0
(-7715 3660);
DISPLAY 0.659574 (-7715 3660);
PAINT MONO (-7715 3660);
DISPLAY INVISIBLE (-7715 3660);
FORCEPROP 2 LAST CDS_LIB logical_power
J 0
(-7725 3600);
PAINT MONO (-7725 3600);
DISPLAY INVISIBLE (-7725 3600);
FORCEPROP 1 LAST HDL_POWER GND
J 1
(-7700 3525);
DISPLAY 0.872340 (-7700 3525);
PAINT GREEN (-7700 3525);
DISPLAY INVISIBLE (-7700 3525);
FORCEPROP 1 LAST PATH I64
J 0
(-7650 3600);
DISPLAY 0.872340 (-7650 3600);
PAINT AQUA (-7650 3600);
DISPLAY INVISIBLE (-7650 3600);
FORCEADD Q_CAP..1
R 2
(-7725 3900);
FORCEPROP 1 LAST PART_NUMBER CH5104KEB02
J 2
(-7775 3750);
DISPLAY 0.510638 (-7775 3750);
DISPLAY INVISIBLE (-7775 3750);
FORCEPROP 1 LAST MATERIAL EMPTY
J 2
(-7775 3800);
DISPLAY 0.510638 (-7775 3800);
FORCEPROP 1 LAST TOLERANCE 10%
J 2
(-7775 3850);
DISPLAY 0.510638 (-7775 3850);
FORCEPROP 1 LAST VOLTAGE 25V
J 2
(-7775 3900);
DISPLAY 0.510638 (-7775 3900);
FORCEPROP 1 LAST VALUE 1UF
J 2
(-7775 3950);
DISPLAY 0.510638 (-7775 3950);
FORCEPROP 1 LAST PACK_TYPE C0402
J 2
(-7775 3700);
DISPLAY 0.510638 (-7775 3700);
FORCEPROP 1 LAST $LOCATION C614
J 2
(-7775 4000);
DISPLAY 0.978723 (-7775 4000);
FORCEPROP 1 LASTPIN (-7725 4000) $PN 1
J 2
(-7735 3980);
DISPLAY 0.787234 (-7735 3980);
FORCEPROP 1 LASTPIN (-7725 3800) $PN 2
J 2
(-7735 3780);
DISPLAY 0.787234 (-7735 3780);
FORCEPROP 2 LAST CDS_LIB pure_quanta
J 0
(-7725 3900);
PAINT MONO (-7725 3900);
DISPLAY INVISIBLE (-7725 3900);
FORCEPROP 1 LAST PATH I65
J 2
(-7775 4050);
DISPLAY 0.978723 (-7775 4050);
PAINT WHITE (-7775 4050);
DISPLAY INVISIBLE (-7775 4050);
FORCEPROP 2 LAST CDS_LOCATION C614
J 0
(-7775 4100);
DISPLAY 1.021277 (-7775 4100);
DISPLAY INVISIBLE (-7775 4100);
FORCEPROP 2 LAST $SEC 1
J 0
(-7775 4100);
DISPLAY 0.680851 (-7775 4100);
PAINT MONO (-7775 4100);
DISPLAY INVISIBLE (-7775 4100);
FORCEPROP 2 LAST CDS_SEC 1
J 0
(-7775 4100);
DISPLAY 1.021277 (-7775 4100);
DISPLAY INVISIBLE (-7775 4100);
FORCEADD Q_CAP..1
R 2
(-7750 -650);
FORCEPROP 1 LAST PART_NUMBER CH5104KEB02
J 2
(-7800 -800);
DISPLAY 0.510638 (-7800 -800);
DISPLAY INVISIBLE (-7800 -800);
FORCEPROP 1 LAST VALUE 1UF
J 2
(-7800 -600);
DISPLAY 0.510638 (-7800 -600);
FORCEPROP 1 LAST VOLTAGE 25V
J 2
(-7800 -650);
DISPLAY 0.510638 (-7800 -650);
FORCEPROP 1 LAST TOLERANCE 10%
J 2
(-7800 -700);
DISPLAY 0.510638 (-7800 -700);
FORCEPROP 1 LAST PACK_TYPE C0402
J 2
(-7800 -850);
DISPLAY 0.510638 (-7800 -850);
FORCEPROP 1 LAST MATERIAL EMPTY
J 2
(-7800 -750);
DISPLAY 0.510638 (-7800 -750);
FORCEPROP 1 LAST $LOCATION C613
J 2
(-7800 -550);
DISPLAY 0.978723 (-7800 -550);
FORCEPROP 1 LASTPIN (-7750 -550) $PN 1
J 2
(-7760 -570);
DISPLAY 0.787234 (-7760 -570);
FORCEPROP 1 LASTPIN (-7750 -750) $PN 2
J 2
(-7760 -770);
DISPLAY 0.787234 (-7760 -770);
FORCEPROP 2 LAST CDS_LIB pure_quanta
J 0
(-7750 -650);
PAINT MONO (-7750 -650);
DISPLAY INVISIBLE (-7750 -650);
FORCEPROP 1 LAST PATH I68
J 2
(-7800 -500);
DISPLAY 0.978723 (-7800 -500);
PAINT WHITE (-7800 -500);
DISPLAY INVISIBLE (-7800 -500);
FORCEPROP 2 LAST CDS_LOCATION C613
J 0
(-7800 -450);
DISPLAY 1.021277 (-7800 -450);
DISPLAY INVISIBLE (-7800 -450);
FORCEPROP 2 LAST $SEC 1
J 0
(-7800 -450);
DISPLAY 0.680851 (-7800 -450);
PAINT MONO (-7800 -450);
DISPLAY INVISIBLE (-7800 -450);
FORCEPROP 2 LAST CDS_SEC 1
J 0
(-7800 -450);
DISPLAY 1.021277 (-7800 -450);
DISPLAY INVISIBLE (-7800 -450);
FORCEADD Q_RES..2
(-7600 875);
FORCEPROP 1 LAST PART_NUMBER CS31002FB08
J 0
(-7560 725);
DISPLAY 0.510638 (-7560 725);
DISPLAY INVISIBLE (-7560 725);
FORCEPROP 1 LAST MATERIAL EMPTY
J 0
(-7560 775);
DISPLAY 0.510638 (-7560 775);
PAINT RED (-7560 775);
FORCEPROP 1 LAST TOLERANCE 1%
J 0
(-7555 875);
DISPLAY 0.510638 (-7555 875);
FORCEPROP 1 LAST VALUE 10K
J 0
(-7555 925);
DISPLAY 0.510638 (-7555 925);
FORCEPROP 1 LAST WATTAGE 1/16W
J 0
(-7560 825);
DISPLAY 0.510638 (-7560 825);
FORCEPROP 1 LAST PACK_TYPE 0402LF
J 0
(-7560 675);
DISPLAY 0.510638 (-7560 675);
FORCEPROP 1 LAST $LOCATION R704
J 0
(-7555 975);
DISPLAY 1.021277 (-7555 975);
FORCEPROP 1 LASTPIN (-7600 975) $PN 1
J 0
(-7595 937);
DISPLAY 0.787234 (-7595 937);
FORCEPROP 1 LASTPIN (-7600 775) $PN 2
J 0
(-7595 785);
DISPLAY 0.787234 (-7595 785);
FORCEPROP 2 LAST CDS_LIB pure_quanta
J 0
(-7600 875);
PAINT MONO (-7600 875);
DISPLAY INVISIBLE (-7600 875);
FORCEPROP 1 LAST PATH I75
J 0
(-7550 1050);
DISPLAY 0.978723 (-7550 1050);
PAINT WHITE (-7550 1050);
DISPLAY INVISIBLE (-7550 1050);
FORCEPROP 2 LAST CDS_LOCATION R704
J 0
(-7550 1100);
DISPLAY 1.021277 (-7550 1100);
DISPLAY INVISIBLE (-7550 1100);
FORCEPROP 2 LAST $SEC 1
J 0
(-7550 1100);
DISPLAY 0.680851 (-7550 1100);
PAINT MONO (-7550 1100);
DISPLAY INVISIBLE (-7550 1100);
FORCEPROP 2 LAST CDS_SEC 1
J 0
(-7550 1100);
DISPLAY 1.021277 (-7550 1100);
DISPLAY INVISIBLE (-7550 1100);
FORCEADD Q_RES..2
(-7625 -650);
FORCEPROP 1 LAST PART_NUMBER CS31002FB08
J 0
(-7585 -800);
DISPLAY 0.510638 (-7585 -800);
DISPLAY INVISIBLE (-7585 -800);
FORCEPROP 1 LAST WATTAGE 1/16W
J 0
(-7585 -700);
DISPLAY 0.510638 (-7585 -700);
FORCEPROP 1 LAST VALUE 10K
J 0
(-7580 -600);
DISPLAY 0.510638 (-7580 -600);
FORCEPROP 1 LAST PACK_TYPE 0402LF
J 0
(-7585 -850);
DISPLAY 0.510638 (-7585 -850);
FORCEPROP 1 LAST TOLERANCE 1%
J 0
(-7580 -650);
DISPLAY 0.510638 (-7580 -650);
FORCEPROP 1 LAST MATERIAL EMPTY
J 0
(-7585 -750);
DISPLAY 0.510638 (-7585 -750);
PAINT RED (-7585 -750);
FORCEPROP 1 LAST $LOCATION R702
J 0
(-7580 -550);
DISPLAY 1.021277 (-7580 -550);
FORCEPROP 1 LASTPIN (-7625 -550) $PN 1
J 0
(-7620 -588);
DISPLAY 0.787234 (-7620 -588);
FORCEPROP 1 LASTPIN (-7625 -750) $PN 2
J 0
(-7620 -740);
DISPLAY 0.787234 (-7620 -740);
FORCEPROP 2 LAST CDS_LIB pure_quanta
J 0
(-7625 -650);
PAINT MONO (-7625 -650);
DISPLAY INVISIBLE (-7625 -650);
FORCEPROP 1 LAST PATH I76
J 0
(-7575 -475);
DISPLAY 0.978723 (-7575 -475);
PAINT WHITE (-7575 -475);
DISPLAY INVISIBLE (-7575 -475);
FORCEPROP 2 LAST CDS_LOCATION R702
J 0
(-7575 -425);
DISPLAY 1.021277 (-7575 -425);
DISPLAY INVISIBLE (-7575 -425);
FORCEPROP 2 LAST $SEC 1
J 0
(-7575 -425);
DISPLAY 0.680851 (-7575 -425);
PAINT MONO (-7575 -425);
DISPLAY INVISIBLE (-7575 -425);
FORCEPROP 2 LAST CDS_SEC 1
J 0
(-7575 -425);
DISPLAY 1.021277 (-7575 -425);
DISPLAY INVISIBLE (-7575 -425);
FORCEADD Q_RES..2
(-7600 3900);
FORCEPROP 1 LAST PART_NUMBER CS31002FB08
J 0
(-7560 3725);
DISPLAY 0.510638 (-7560 3725);
DISPLAY INVISIBLE (-7560 3725);
FORCEPROP 1 LAST VALUE 10K
J 0
(-7555 3925);
DISPLAY 0.510638 (-7555 3925);
FORCEPROP 1 LAST TOLERANCE 1%
J 0
(-7555 3875);
DISPLAY 0.510638 (-7555 3875);
FORCEPROP 1 LAST MATERIAL EMPTY
J 0
(-7560 3775);
DISPLAY 0.510638 (-7560 3775);
PAINT RED (-7560 3775);
FORCEPROP 1 LAST PACK_TYPE 0402LF
J 0
(-7560 3675);
DISPLAY 0.510638 (-7560 3675);
FORCEPROP 1 LAST WATTAGE 1/16W
J 0
(-7560 3825);
DISPLAY 0.510638 (-7560 3825);
FORCEPROP 1 LAST $LOCATION R703
J 0
(-7555 4000);
DISPLAY 0.978723 (-7555 4000);
FORCEPROP 1 LASTPIN (-7600 4000) $PN 1
J 0
(-7595 3962);
DISPLAY 0.787234 (-7595 3962);
FORCEPROP 1 LASTPIN (-7600 3800) $PN 2
J 0
(-7595 3810);
DISPLAY 0.787234 (-7595 3810);
FORCEPROP 2 LAST CDS_LIB pure_quanta
J 0
(-7600 3900);
PAINT MONO (-7600 3900);
DISPLAY INVISIBLE (-7600 3900);
FORCEPROP 1 LAST PATH I79
J 0
(-7550 4075);
DISPLAY 0.978723 (-7550 4075);
PAINT WHITE (-7550 4075);
DISPLAY INVISIBLE (-7550 4075);
FORCEPROP 2 LAST CDS_LOCATION R703
J 0
(-7550 4125);
DISPLAY 1.021277 (-7550 4125);
DISPLAY INVISIBLE (-7550 4125);
FORCEPROP 2 LAST $SEC 1
J 0
(-7550 4125);
DISPLAY 0.680851 (-7550 4125);
PAINT MONO (-7550 4125);
DISPLAY INVISIBLE (-7550 4125);
FORCEPROP 2 LAST CDS_SEC 1
J 0
(-7550 4125);
DISPLAY 1.021277 (-7550 4125);
DISPLAY INVISIBLE (-7550 4125);
FORCEADD OFFPAGE..2
(-2450 4200);
FORCEPROP 2 LAST $XR3 101 
J 0
(-1961 4200);
DISPLAY 0.638298 (-1961 4200);
PAINT MONO (-1961 4200);
FORCEPROP 2 LAST $XR2 100 
J 0
(-2081 4200);
DISPLAY 0.638298 (-2081 4200);
PAINT MONO (-2081 4200);
FORCEPROP 2 LAST $XR1 99 
J 0
(-2171 4200);
DISPLAY 0.638298 (-2171 4200);
PAINT MONO (-2171 4200);
FORCEPROP 2 LAST $XR0 98 
J 0
(-2261 4200);
DISPLAY 0.638298 (-2261 4200);
PAINT MONO (-2261 4200);
FORCEPROP 2 LAST CDS_LIB standard
J 0
(-2450 4200);
DISPLAY INVISIBLE (-2450 4200);
FORCEPROP 1 LAST OFFPAGE TRUE
J 0
(-2125 4075);
DISPLAY 0.872340 (-2125 4075);
PAINT GREEN (-2125 4075);
DISPLAY INVISIBLE (-2125 4075);
FORCEPROP 1 LAST COMMENT_BODY TRUE
J 0
(-2495 4105);
DISPLAY 0.872340 (-2495 4105);
PAINT GREEN (-2495 4105);
DISPLAY INVISIBLE (-2495 4105);
FORCEPROP 2 LAST PATH I80
J 0
(-1850 4250);
DISPLAY 1.021277 (-1850 4250);
DISPLAY INVISIBLE (-1850 4250);
FORCEADD UNIVERSAL_POWER..1
(-3175 4700);
FORCEPROP 3 LASTPIN (-3175 4650) SIG_NAME PVCCD_HV_CPU1\g
J 0
(-3165 4660);
DISPLAY 0.659574 (-3165 4660);
PAINT MONO (-3165 4660);
DISPLAY INVISIBLE (-3165 4660);
FORCEPROP 1 LAST HDL_POWER PVCCD_HV_CPU1
J 1
(-3175 4750);
DISPLAY 0.872340 (-3175 4750);
PAINT GREEN (-3175 4750);
FORCEPROP 2 LAST CDS_LIB logical_power
J 0
(-3175 4700);
PAINT MONO (-3175 4700);
DISPLAY INVISIBLE (-3175 4700);
FORCEPROP 1 LAST PATH I81
J 0
(-3125 4725);
DISPLAY 0.872340 (-3125 4725);
PAINT AQUA (-3125 4725);
DISPLAY INVISIBLE (-3125 4725);
FORCEADD Q_RES..2
(-3175 4450);
FORCEPROP 1 LAST PART_NUMBER CS21002FB06
J 0
(-3135 4325);
DISPLAY 0.638298 (-3135 4325);
DISPLAY INVISIBLE (-3135 4325);
FORCEPROP 1 LAST TOLERANCE 1%
J 0
(-3130 4475);
DISPLAY 0.638298 (-3130 4475);
FORCEPROP 1 LAST VALUE 1K
J 0
(-3130 4525);
DISPLAY 0.638298 (-3130 4525);
FORCEPROP 1 LAST PACK_TYPE 0402LF
J 0
(-3135 4275);
DISPLAY 0.638298 (-3135 4275);
FORCEPROP 1 LAST WATTAGE 1/16W
J 0
(-3135 4425);
DISPLAY 0.638298 (-3135 4425);
FORCEPROP 1 LAST MATERIAL CHIP
J 0
(-3135 4375);
DISPLAY 0.638298 (-3135 4375);
FORCEPROP 1 LAST $LOCATION R820
J 0
(-3130 4575);
DISPLAY 0.978723 (-3130 4575);
FORCEPROP 1 LASTPIN (-3175 4550) $PN 1
J 0
(-3170 4512);
DISPLAY 0.787234 (-3170 4512);
FORCEPROP 1 LASTPIN (-3175 4350) $PN 2
J 0
(-3170 4360);
DISPLAY 0.787234 (-3170 4360);
FORCEPROP 2 LAST CDS_LIB pure_quanta
J 0
(-3175 4450);
PAINT MONO (-3175 4450);
DISPLAY INVISIBLE (-3175 4450);
FORCEPROP 1 LAST PATH I82
J 0
(-3125 4625);
DISPLAY 0.978723 (-3125 4625);
PAINT WHITE (-3125 4625);
DISPLAY INVISIBLE (-3125 4625);
FORCEPROP 1 LAST $LOCATION R820
J 0
(-3125 4675);
DISPLAY 1.021277 (-3125 4675);
DISPLAY INVISIBLE (-3125 4675);
FORCEPROP 2 LAST CDS_LOCATION R820
J 0
(-3125 4675);
DISPLAY 1.021277 (-3125 4675);
DISPLAY INVISIBLE (-3125 4675);
FORCEPROP 2 LAST $SEC 1
J 0
(-3125 4675);
DISPLAY 0.680851 (-3125 4675);
PAINT MONO (-3125 4675);
DISPLAY INVISIBLE (-3125 4675);
FORCEPROP 2 LAST CDS_SEC 1
J 0
(-3125 4675);
DISPLAY 1.021277 (-3125 4675);
DISPLAY INVISIBLE (-3125 4675);
FORCEADD UNIVERSAL_POWER..1
(-3175 3175);
FORCEPROP 3 LASTPIN (-3175 3125) SIG_NAME PVCCD_HV_CPU1\g
J 0
(-3165 3135);
DISPLAY 0.659574 (-3165 3135);
PAINT MONO (-3165 3135);
DISPLAY INVISIBLE (-3165 3135);
FORCEPROP 1 LAST HDL_POWER PVCCD_HV_CPU1
J 1
(-3175 3225);
DISPLAY 0.872340 (-3175 3225);
PAINT GREEN (-3175 3225);
FORCEPROP 2 LAST CDS_LIB logical_power
J 0
(-3175 3175);
PAINT MONO (-3175 3175);
DISPLAY INVISIBLE (-3175 3175);
FORCEPROP 1 LAST PATH I83
J 0
(-3125 3200);
DISPLAY 0.872340 (-3125 3200);
PAINT AQUA (-3125 3200);
DISPLAY INVISIBLE (-3125 3200);
FORCEADD Q_RES..2
(-3175 2925);
FORCEPROP 1 LAST PART_NUMBER CS21002FB06
J 0
(-3135 2800);
DISPLAY 0.638298 (-3135 2800);
DISPLAY INVISIBLE (-3135 2800);
FORCEPROP 1 LAST TOLERANCE 1%
J 0
(-3130 2950);
DISPLAY 0.638298 (-3130 2950);
FORCEPROP 1 LAST VALUE 1K
J 0
(-3130 3000);
DISPLAY 0.638298 (-3130 3000);
FORCEPROP 1 LAST PACK_TYPE 0402LF
J 0
(-3135 2750);
DISPLAY 0.638298 (-3135 2750);
FORCEPROP 1 LAST WATTAGE 1/16W
J 0
(-3135 2900);
DISPLAY 0.638298 (-3135 2900);
FORCEPROP 1 LAST MATERIAL CHIP
J 0
(-3135 2850);
DISPLAY 0.638298 (-3135 2850);
FORCEPROP 1 LAST $LOCATION R821
J 0
(-3130 3050);
DISPLAY 0.978723 (-3130 3050);
FORCEPROP 1 LASTPIN (-3175 3025) $PN 1
J 0
(-3170 2987);
DISPLAY 0.787234 (-3170 2987);
FORCEPROP 1 LASTPIN (-3175 2825) $PN 2
J 0
(-3170 2835);
DISPLAY 0.787234 (-3170 2835);
FORCEPROP 2 LAST CDS_LIB pure_quanta
J 0
(-3175 2925);
PAINT MONO (-3175 2925);
DISPLAY INVISIBLE (-3175 2925);
FORCEPROP 1 LAST PATH I84
J 0
(-3125 3100);
DISPLAY 0.978723 (-3125 3100);
PAINT WHITE (-3125 3100);
DISPLAY INVISIBLE (-3125 3100);
FORCEPROP 1 LAST $LOCATION R821
J 0
(-3125 3150);
DISPLAY 1.021277 (-3125 3150);
DISPLAY INVISIBLE (-3125 3150);
FORCEPROP 2 LAST CDS_LOCATION R821
J 0
(-3125 3150);
DISPLAY 1.021277 (-3125 3150);
DISPLAY INVISIBLE (-3125 3150);
FORCEPROP 2 LAST $SEC 1
J 0
(-3125 3150);
DISPLAY 0.680851 (-3125 3150);
PAINT MONO (-3125 3150);
DISPLAY INVISIBLE (-3125 3150);
FORCEPROP 2 LAST CDS_SEC 1
J 0
(-3125 3150);
DISPLAY 1.021277 (-3125 3150);
DISPLAY INVISIBLE (-3125 3150);
FORCEADD OFFPAGE..2
(-2450 2675);
FORCEPROP 2 LAST $XR3 105 
J 0
(-1901 2675);
DISPLAY 0.638298 (-1901 2675);
PAINT MONO (-1901 2675);
FORCEPROP 2 LAST $XR2 104 
J 0
(-2021 2675);
DISPLAY 0.638298 (-2021 2675);
PAINT MONO (-2021 2675);
FORCEPROP 2 LAST $XR1 103 
J 0
(-2141 2675);
DISPLAY 0.638298 (-2141 2675);
PAINT MONO (-2141 2675);
FORCEPROP 2 LAST $XR0 102 
J 0
(-2261 2675);
DISPLAY 0.638298 (-2261 2675);
PAINT MONO (-2261 2675);
FORCEPROP 2 LAST CDS_LIB standard
J 0
(-2450 2675);
DISPLAY INVISIBLE (-2450 2675);
FORCEPROP 1 LAST OFFPAGE TRUE
J 0
(-2125 2550);
DISPLAY 0.872340 (-2125 2550);
PAINT GREEN (-2125 2550);
DISPLAY INVISIBLE (-2125 2550);
FORCEPROP 1 LAST COMMENT_BODY TRUE
J 0
(-2495 2580);
DISPLAY 0.872340 (-2495 2580);
PAINT GREEN (-2495 2580);
DISPLAY INVISIBLE (-2495 2580);
FORCEPROP 2 LAST PATH I85
J 0
(-1800 2725);
DISPLAY 1.021277 (-1800 2725);
DISPLAY INVISIBLE (-1800 2725);
FORCEADD OFFPAGE..2
(-2475 1175);
FORCEPROP 2 LAST $XR3 109 
J 0
(-1926 1175);
DISPLAY 0.638298 (-1926 1175);
PAINT MONO (-1926 1175);
FORCEPROP 2 LAST $XR2 108 
J 0
(-2046 1175);
DISPLAY 0.638298 (-2046 1175);
PAINT MONO (-2046 1175);
FORCEPROP 2 LAST $XR1 107 
J 0
(-2166 1175);
DISPLAY 0.638298 (-2166 1175);
PAINT MONO (-2166 1175);
FORCEPROP 2 LAST $XR0 106 
J 0
(-2286 1175);
DISPLAY 0.638298 (-2286 1175);
PAINT MONO (-2286 1175);
FORCEPROP 2 LAST CDS_LIB standard
J 0
(-2475 1175);
DISPLAY INVISIBLE (-2475 1175);
FORCEPROP 1 LAST OFFPAGE TRUE
J 0
(-2150 1050);
DISPLAY 0.872340 (-2150 1050);
PAINT GREEN (-2150 1050);
DISPLAY INVISIBLE (-2150 1050);
FORCEPROP 1 LAST COMMENT_BODY TRUE
J 0
(-2520 1080);
DISPLAY 0.872340 (-2520 1080);
PAINT GREEN (-2520 1080);
DISPLAY INVISIBLE (-2520 1080);
FORCEPROP 2 LAST PATH I86
J 0
(-1825 1225);
DISPLAY 1.021277 (-1825 1225);
DISPLAY INVISIBLE (-1825 1225);
FORCEADD UNIVERSAL_POWER..1
(-3175 1675);
FORCEPROP 3 LASTPIN (-3175 1625) SIG_NAME PVCCD_HV_CPU1\g
J 0
(-3165 1635);
DISPLAY 0.659574 (-3165 1635);
PAINT MONO (-3165 1635);
DISPLAY INVISIBLE (-3165 1635);
FORCEPROP 1 LAST HDL_POWER PVCCD_HV_CPU1
J 1
(-3175 1725);
DISPLAY 0.872340 (-3175 1725);
PAINT GREEN (-3175 1725);
FORCEPROP 2 LAST CDS_LIB logical_power
J 0
(-3175 1675);
PAINT MONO (-3175 1675);
DISPLAY INVISIBLE (-3175 1675);
FORCEPROP 1 LAST PATH I87
J 0
(-3125 1700);
DISPLAY 0.872340 (-3125 1700);
PAINT AQUA (-3125 1700);
DISPLAY INVISIBLE (-3125 1700);
FORCEADD Q_RES..2
(-3175 1425);
FORCEPROP 1 LAST PART_NUMBER CS21002FB06
J 0
(-3135 1300);
DISPLAY 0.638298 (-3135 1300);
DISPLAY INVISIBLE (-3135 1300);
FORCEPROP 1 LAST VALUE 1K
J 0
(-3130 1500);
DISPLAY 0.638298 (-3130 1500);
FORCEPROP 1 LAST TOLERANCE 1%
J 0
(-3130 1450);
DISPLAY 0.638298 (-3130 1450);
FORCEPROP 1 LAST PACK_TYPE 0402LF
J 0
(-3135 1250);
DISPLAY 0.638298 (-3135 1250);
FORCEPROP 1 LAST WATTAGE 1/16W
J 0
(-3135 1400);
DISPLAY 0.638298 (-3135 1400);
FORCEPROP 1 LAST MATERIAL CHIP
J 0
(-3135 1350);
DISPLAY 0.638298 (-3135 1350);
FORCEPROP 1 LAST $LOCATION R822
J 0
(-3130 1550);
DISPLAY 0.978723 (-3130 1550);
FORCEPROP 1 LASTPIN (-3175 1525) $PN 1
J 0
(-3170 1487);
DISPLAY 0.787234 (-3170 1487);
FORCEPROP 1 LASTPIN (-3175 1325) $PN 2
J 0
(-3170 1335);
DISPLAY 0.787234 (-3170 1335);
FORCEPROP 2 LAST CDS_LIB pure_quanta
J 0
(-3175 1425);
PAINT MONO (-3175 1425);
DISPLAY INVISIBLE (-3175 1425);
FORCEPROP 1 LAST PATH I88
J 0
(-3125 1600);
DISPLAY 0.978723 (-3125 1600);
PAINT WHITE (-3125 1600);
DISPLAY INVISIBLE (-3125 1600);
FORCEPROP 1 LAST $LOCATION R822
J 0
(-3125 1650);
DISPLAY 1.021277 (-3125 1650);
DISPLAY INVISIBLE (-3125 1650);
FORCEPROP 2 LAST CDS_LOCATION R822
J 0
(-3125 1650);
DISPLAY 1.021277 (-3125 1650);
DISPLAY INVISIBLE (-3125 1650);
FORCEPROP 2 LAST $SEC 1
J 0
(-3125 1650);
DISPLAY 0.680851 (-3125 1650);
PAINT MONO (-3125 1650);
DISPLAY INVISIBLE (-3125 1650);
FORCEPROP 2 LAST CDS_SEC 1
J 0
(-3125 1650);
DISPLAY 1.021277 (-3125 1650);
DISPLAY INVISIBLE (-3125 1650);
FORCEADD UNIVERSAL_POWER..1
(-3200 150);
FORCEPROP 3 LASTPIN (-3200 100) SIG_NAME PVCCD_HV_CPU1\g
J 0
(-3190 110);
DISPLAY 0.659574 (-3190 110);
PAINT MONO (-3190 110);
DISPLAY INVISIBLE (-3190 110);
FORCEPROP 1 LAST HDL_POWER PVCCD_HV_CPU1
J 1
(-3200 200);
DISPLAY 0.872340 (-3200 200);
PAINT GREEN (-3200 200);
FORCEPROP 2 LAST CDS_LIB logical_power
J 0
(-3200 150);
PAINT MONO (-3200 150);
DISPLAY INVISIBLE (-3200 150);
FORCEPROP 1 LAST PATH I89
J 0
(-3150 175);
DISPLAY 0.872340 (-3150 175);
PAINT AQUA (-3150 175);
DISPLAY INVISIBLE (-3150 175);
FORCEADD Q_RES..2
(-3200 -100);
FORCEPROP 1 LAST PART_NUMBER CS21002FB06
J 0
(-3160 -225);
DISPLAY 0.638298 (-3160 -225);
DISPLAY INVISIBLE (-3160 -225);
FORCEPROP 1 LAST PACK_TYPE 0402LF
J 0
(-3160 -275);
DISPLAY 0.638298 (-3160 -275);
FORCEPROP 1 LAST VALUE 1K
J 0
(-3155 -25);
DISPLAY 0.638298 (-3155 -25);
FORCEPROP 1 LAST TOLERANCE 1%
J 0
(-3155 -75);
DISPLAY 0.638298 (-3155 -75);
FORCEPROP 1 LAST WATTAGE 1/16W
J 0
(-3160 -125);
DISPLAY 0.638298 (-3160 -125);
FORCEPROP 1 LAST MATERIAL CHIP
J 0
(-3160 -175);
DISPLAY 0.638298 (-3160 -175);
FORCEPROP 1 LAST $LOCATION R819
J 0
(-3155 25);
DISPLAY 0.978723 (-3155 25);
FORCEPROP 1 LASTPIN (-3200 0) $PN 1
J 0
(-3195 -38);
DISPLAY 0.787234 (-3195 -38);
FORCEPROP 1 LASTPIN (-3200 -200) $PN 2
J 0
(-3195 -190);
DISPLAY 0.787234 (-3195 -190);
FORCEPROP 2 LAST CDS_LIB pure_quanta
J 0
(-3200 -100);
PAINT MONO (-3200 -100);
DISPLAY INVISIBLE (-3200 -100);
FORCEPROP 1 LAST PATH I90
J 0
(-3150 75);
DISPLAY 0.978723 (-3150 75);
PAINT WHITE (-3150 75);
DISPLAY INVISIBLE (-3150 75);
FORCEPROP 1 LAST $LOCATION R819
J 0
(-3150 125);
DISPLAY 1.021277 (-3150 125);
DISPLAY INVISIBLE (-3150 125);
FORCEPROP 2 LAST CDS_LOCATION R819
J 0
(-3150 125);
DISPLAY 1.021277 (-3150 125);
DISPLAY INVISIBLE (-3150 125);
FORCEPROP 2 LAST $SEC 1
J 0
(-3150 125);
DISPLAY 0.680851 (-3150 125);
PAINT MONO (-3150 125);
DISPLAY INVISIBLE (-3150 125);
FORCEPROP 2 LAST CDS_SEC 1
J 0
(-3150 125);
DISPLAY 1.021277 (-3150 125);
DISPLAY INVISIBLE (-3150 125);
FORCEADD OFFPAGE..2
(-2475 -350);
FORCEPROP 2 LAST $XR3 113 
J 0
(-1926 -350);
DISPLAY 0.638298 (-1926 -350);
PAINT MONO (-1926 -350);
FORCEPROP 2 LAST $XR2 112 
J 0
(-2046 -350);
DISPLAY 0.638298 (-2046 -350);
PAINT MONO (-2046 -350);
FORCEPROP 2 LAST $XR1 111 
J 0
(-2166 -350);
DISPLAY 0.638298 (-2166 -350);
PAINT MONO (-2166 -350);
FORCEPROP 2 LAST $XR0 110 
J 0
(-2286 -350);
DISPLAY 0.638298 (-2286 -350);
PAINT MONO (-2286 -350);
FORCEPROP 2 LAST CDS_LIB standard
J 0
(-2475 -350);
DISPLAY INVISIBLE (-2475 -350);
FORCEPROP 1 LAST OFFPAGE TRUE
J 0
(-2150 -475);
DISPLAY 0.872340 (-2150 -475);
PAINT GREEN (-2150 -475);
DISPLAY INVISIBLE (-2150 -475);
FORCEPROP 1 LAST COMMENT_BODY TRUE
J 0
(-2520 -445);
DISPLAY 0.872340 (-2520 -445);
PAINT GREEN (-2520 -445);
DISPLAY INVISIBLE (-2520 -445);
FORCEPROP 2 LAST PATH I91
J 0
(-1825 -300);
DISPLAY 1.021277 (-1825 -300);
DISPLAY INVISIBLE (-1825 -300);
FORCEADD QUANTA_TITLE_BLOCK_C..1
(-500 -1350);
FORCEPROP 0 LAST CDS_CON_LAST_MODIFIED Fri Aug 25 14:01:50 2023
J 0
(-2385 -1335);
PAINT MONO (-2385 -1335);
DISPLAY INVISIBLE (-2385 -1335);
FORCEPROP 2 LAST CUSTOM_TXT_CDS <XR_PAGE_TITLE>
J 0
(-8390 3900);
DISPLAY 0.638298 (-8390 3900);
PAINT PINK (-8390 3900);
DISPLAY INVISIBLE (-8390 3900);
FORCEPROP 2 LAST CUSTOM_TXT_CDS <NAME_2>
J 0
(-3675 -1300);
FORCEPROP 2 LAST CUSTOM_TXT_CDS <CON_LAST_MODIFIED>
J 0
(-2385 -1335);
DISPLAY 0.978723 (-2385 -1335);
FORCEPROP 2 LAST CUSTOM_TXT_CDS <CON_PAGE_NUM> OF <CON_TOTAL_PAGES>
J 0
(-946 -1332);
DISPLAY 0.978723 (-946 -1332);
FORCEPROP 2 LAST CUSTOM_TXT_CDS <Q_NUMBER>
J 0
(-1903 -1247);
DISPLAY 1.212766 (-1903 -1247);
FORCEPROP 2 LAST CUSTOM_TXT_CDS <Q_PROJ>
J 0
(-2882 -1248);
DISPLAY 1.212766 (-2882 -1248);
FORCEPROP 2 LAST CUSTOM_TXT_CDS <Q_REV>
J 0
(-684 -1247);
DISPLAY 1.212766 (-684 -1247);
FORCEPROP 2 LAST CUSTOM_TXT_CDS <NAME_1>
J 0
(-3675 -1175);
FORCEPROP 1 LAST Q_TITLE SPR CPU1 - DDR RESET PLD TO DIMM
J 0
(-9766 -1324);
DISPLAY 2.446809 (-9766 -1324);
PAINT GREEN (-9766 -1324);
FORCEPROP 1 LAST Q_DEPT 
J 1
(-4263 -1301);
DISPLAY 1.957447 (-4263 -1301);
PAINT GREEN (-4263 -1301);
FORCEPROP 2 LAST CDS_XR_PAGE_TITLE CR-130 : @S9S_MB_2U_LIB.S9S_MB_2U(SCH_1):PAGE130
J 0
(-8390 3900);
DISPLAY 0.638298 (-8390 3900);
PAINT PINK (-8390 3900);
DISPLAY INVISIBLE (-8390 3900);
FORCEPROP 1 LAST COMMENT_BODY TRUE
J 0
(-488 -1363);
DISPLAY 0.978723 (-488 -1363);
PAINT GREEN (-488 -1363);
DISPLAY INVISIBLE (-488 -1363);
FORCEPROP 2 LAST PAGE_BORDER TRUE
J 0
(-8390 3900);
DISPLAY 0.638298 (-8390 3900);
PAINT PINK (-8390 3900);
DISPLAY INVISIBLE (-8390 3900);
FORCEPROP 1 LAST CDS_LMAN_SYM_OUTLINE -9475,6775,100,-125
J 0
(-500 -1350);
DISPLAY 0.468085 (-500 -1350);
PAINT GREEN (-500 -1350);
DISPLAY INVISIBLE (-500 -1350);
FORCEPROP 2 LAST CDS_LIB pure_quanta
J 0
(-500 -1350);
PAINT MONO (-500 -1350);
DISPLAY INVISIBLE (-500 -1350);
FORCEADD DNS..2
(-7720 3895);
PAINT RED (-7720 3895);
FORCEPROP 2 LAST CDS_LIB mstr_misc
J 0
(-7720 3895);
PAINT MONO (-7720 3895);
DISPLAY INVISIBLE (-7720 3895);
FORCEPROP 1 LAST COMMENT_BODY TRUE
J 0
(-7720 3895);
DISPLAY INVISIBLE (-7720 3895);
FORCEADD DNS..2
(-7595 3895);
PAINT RED (-7595 3895);
FORCEPROP 2 LAST CDS_LIB mstr_misc
J 0
(-7595 3895);
PAINT MONO (-7595 3895);
DISPLAY INVISIBLE (-7595 3895);
FORCEPROP 1 LAST COMMENT_BODY TRUE
J 0
(-7595 3895);
DISPLAY INVISIBLE (-7595 3895);
FORCEADD DNS..2
(-7620 2395);
PAINT RED (-7620 2395);
FORCEPROP 2 LAST CDS_LIB mstr_misc
J 0
(-7620 2395);
PAINT MONO (-7620 2395);
DISPLAY INVISIBLE (-7620 2395);
FORCEPROP 1 LAST COMMENT_BODY TRUE
J 0
(-7620 2395);
DISPLAY INVISIBLE (-7620 2395);
FORCEADD DNS..2
(-7620 -655);
PAINT RED (-7620 -655);
FORCEPROP 2 LAST CDS_LIB mstr_misc
J 0
(-7620 -655);
PAINT MONO (-7620 -655);
DISPLAY INVISIBLE (-7620 -655);
FORCEPROP 1 LAST COMMENT_BODY TRUE
J 0
(-7620 -655);
DISPLAY INVISIBLE (-7620 -655);
FORCEADD DNS..2
(-7720 2370);
PAINT RED (-7720 2370);
FORCEPROP 2 LAST CDS_LIB mstr_misc
J 0
(-7720 2370);
PAINT MONO (-7720 2370);
DISPLAY INVISIBLE (-7720 2370);
FORCEPROP 1 LAST COMMENT_BODY TRUE
J 0
(-7720 2370);
DISPLAY INVISIBLE (-7720 2370);
FORCEADD DNS..2
(-7720 870);
PAINT RED (-7720 870);
FORCEPROP 2 LAST CDS_LIB mstr_misc
J 0
(-7720 870);
PAINT MONO (-7720 870);
DISPLAY INVISIBLE (-7720 870);
FORCEPROP 1 LAST COMMENT_BODY TRUE
J 0
(-7720 870);
DISPLAY INVISIBLE (-7720 870);
FORCEADD DNS..2
(-7745 -655);
PAINT RED (-7745 -655);
FORCEPROP 2 LAST CDS_LIB mstr_misc
J 0
(-7745 -655);
PAINT MONO (-7745 -655);
DISPLAY INVISIBLE (-7745 -655);
FORCEPROP 1 LAST COMMENT_BODY TRUE
J 0
(-7745 -655);
DISPLAY INVISIBLE (-7745 -655);
FORCEADD DNS..2
(-7595 870);
PAINT RED (-7595 870);
FORCEPROP 2 LAST CDS_LIB mstr_misc
J 0
(-7595 870);
PAINT MONO (-7595 870);
DISPLAY INVISIBLE (-7595 870);
FORCEPROP 1 LAST COMMENT_BODY TRUE
J 0
(-7595 870);
DISPLAY INVISIBLE (-7595 870);
WIRE 16 -1 (-3175 4650)(-3175 4550);
WIRE 16 -1 (-3200 100)(-3200 0);
WIRE 16 -1 (-3175 1625)(-3175 1525);
WIRE 16 -1 (-3175 3125)(-3175 3025);
WIRE 16 -1 (-7725 3725)(-7725 3650);
WIRE 16 -1 (-7600 3725)(-7725 3725);
WIRE 16 -1 (-7725 3800)(-7725 3725);
WIRE 16 -1 (-7725 2200)(-7725 2125);
WIRE 16 -1 (-7625 2200)(-7725 2200);
WIRE 16 -1 (-7725 2275)(-7725 2200);
WIRE 16 -1 (-7725 700)(-7725 625);
WIRE 16 -1 (-7600 700)(-7725 700);
WIRE 16 -1 (-7725 775)(-7725 700);
WIRE 16 -1 (-7750 -825)(-7750 -900);
WIRE 16 -1 (-7625 -825)(-7750 -825);
WIRE 16 -1 (-7750 -750)(-7750 -825);
WIRE 16 -1 (-3200 -200)(-3200 -350);
WIRE 16 -1 (-2525 -350)(-3200 -350);
FORCEPROP 2 LAST SIG_NAME RST_M_GH_CPU1_FPGA_N
J 0
(-3125 -340);
DISPLAY 0.553191 (-3125 -340);
PAINT WHITE (-3125 -340);
WIRE 16 -1 (-5100 -350)(-3200 -350);
WIRE 16 -1 (-7725 1175)(-8575 1175);
FORCEPROP 2 LAST SIG_NAME RST_PLD_CPU1_DRAM_EF_N
J 0
(-8510 1185);
DISPLAY 0.553191 (-8510 1185);
PAINT WHITE (-8510 1185);
WIRE 16 -1 (-7725 975)(-7725 1175);
WIRE 16 -1 (-7600 975)(-7600 1175);
WIRE 16 -1 (-7600 1175)(-7725 1175);
WIRE 16 -1 (-5275 1175)(-7600 1175);
WIRE 16 -1 (-3175 4350)(-3175 4200);
WIRE 16 -1 (-2500 4200)(-3175 4200);
FORCEPROP 2 LAST SIG_NAME RST_M_AB_CPU1_FPGA_N
J 0
(-3100 4210);
DISPLAY 0.553191 (-3100 4210);
PAINT WHITE (-3100 4210);
WIRE 16 -1 (-5075 4200)(-3175 4200);
WIRE 16 -1 (-5075 1175)(-3175 1175);
WIRE 16 -1 (-2525 1175)(-3175 1175);
FORCEPROP 2 LAST SIG_NAME RST_M_EF_CPU1_FPGA_N
J 0
(-3100 1185);
DISPLAY 0.553191 (-3100 1185);
PAINT WHITE (-3100 1185);
WIRE 16 -1 (-3175 1325)(-3175 1175);
WIRE 16 -1 (-3175 2825)(-3175 2675);
WIRE 16 -1 (-2500 2675)(-3175 2675);
FORCEPROP 2 LAST SIG_NAME RST_M_CD_CPU1_FPGA_N
J 0
(-3100 2685);
DISPLAY 0.553191 (-3100 2685);
PAINT WHITE (-3100 2685);
WIRE 16 -1 (-5075 2675)(-3175 2675);
WIRE 16 -1 (-7600 3800)(-7600 3725);
WIRE 16 -1 (-7725 4200)(-8575 4200);
FORCEPROP 2 LAST SIG_NAME RST_PLD_CPU1_DRAM_AB_N
J 0
(-8510 4210);
DISPLAY 0.553191 (-8510 4210);
PAINT WHITE (-8510 4210);
WIRE 16 -1 (-7725 4000)(-7725 4200);
WIRE 16 -1 (-7600 4000)(-7600 4200);
WIRE 16 -1 (-7600 4200)(-7725 4200);
WIRE 16 -1 (-5275 4200)(-7600 4200);
WIRE 16 -1 (-7625 -750)(-7625 -825);
WIRE 16 -1 (-7750 -350)(-8600 -350);
FORCEPROP 2 LAST SIG_NAME RST_PLD_CPU1_DRAM_GH_N
J 0
(-8535 -340);
DISPLAY 0.553191 (-8535 -340);
PAINT WHITE (-8535 -340);
WIRE 16 -1 (-7750 -550)(-7750 -350);
WIRE 16 -1 (-7625 -350)(-7750 -350);
WIRE 16 -1 (-7625 -550)(-7625 -350);
WIRE 16 -1 (-5300 -350)(-7625 -350);
WIRE 16 -1 (-7600 775)(-7600 700);
WIRE 16 -1 (-7625 2300)(-7625 2200);
WIRE 16 -1 (-7725 2675)(-8575 2675);
FORCEPROP 2 LAST SIG_NAME RST_PLD_CPU1_DRAM_CD_N
J 0
(-8510 2685);
DISPLAY 0.553191 (-8510 2685);
PAINT WHITE (-8510 2685);
WIRE 16 -1 (-7725 2475)(-7725 2675);
WIRE 16 -1 (-7625 2675)(-7725 2675);
WIRE 16 -1 (-7625 2500)(-7625 2675);
WIRE 16 -1 (-5275 2675)(-7625 2675);
DOT 1 (-3200 -350);
DOT 1 (-3175 1175);
DOT 1 (-3175 2675);
DOT 1 (-3175 4200);
DOT 1 (-7725 2200);
DOT 1 (-7600 4200);
DOT 1 (-7725 4200);
DOT 1 (-7725 2675);
DOT 1 (-7600 1175);
DOT 1 (-7725 1175);
DOT 1 (-7725 700);
DOT 1 (-7625 -350);
DOT 1 (-7750 -350);
DOT 1 (-7750 -825);
DOT 1 (-7725 3725);
DOT 1 (-7625 2675);
FORCENOTE
20210907 MODIFY FOR GT
(-9250 4900) 0;
DISPLAY LEFT (-9250 4900);
DISPLAY 2.510638 (-9250 4900);
PAINT PINK (-9250 4900);
QUIT
